# S9S_MB_2U (Grand Teton) — schematic netlist excerpt (pin names and nets, part order shuffled) for the footprints in the layout excerpt that follows; sources: Cadence DE-HDL packaged netlist, KiCad conversion of 03242023_DA0F0TMBIJ0_F0T_Motherboard_J_brd_V01_OCP.brd

R1543  Q_RES  0 5% CHIP  pkg 0402LF  page 206 : A = OCP_SFF_CLK_OE_N ; B = FM_DB2000_9_OE_N
PR313  Q_RES  1K 1% EMPTY  pkg 0402LF  page 284 : A = PVCCIN_CPU1_VIN_CSNIN ; B = GND

(kicad_pcb
	(version 20260206)
	(generator "pcbnew")
	(generator_version "10.0")
	(general
		(thickness 1.6)
		(legacy_teardrops no)
	)
	(paper "A4")
	(title_block
		(title "03242023_DA0F0TMBIJ0_F0T_Motherboard_J_brd_V01_OCP.brd")
		(comment 1 "Grand Teton / footprints 4380-4381 of 6105")
	)
	(layers
		(0 "F.Cu" signal "TOP")
		(4 "In1.Cu" signal "GND")
		(6 "In2.Cu" signal "IN1")
		(8 "In3.Cu" signal "GND1")
		(10 "In4.Cu" signal "IN2")
		(12 "In5.Cu" signal "GND2")
		(14 "In6.Cu" signal "IN3")
		(16 "In7.Cu" signal "GND3")
		(18 "In8.Cu" signal "VCC")
		(20 "In9.Cu" signal "VCC1")
		(22 "In10.Cu" signal "GND4")
		(24 "In11.Cu" signal "IN4")
		(26 "In12.Cu" signal "GND5")
		(28 "In13.Cu" signal "IN5")
		(30 "In14.Cu" signal "GND6")
		(32 "In15.Cu" signal "IN6")
		(34 "In16.Cu" signal "GND7")
		(2 "B.Cu" signal "BOTTOM")
		(9 "F.Adhes" user "F.Adhesive")
		(11 "B.Adhes" user "B.Adhesive")
		(13 "F.Paste" user "Package Geometry/Pastemask Top")
		(15 "B.Paste" user "Package Geometry/Pastemask Bottom")
		(5 "F.SilkS" user "Ref Des/Silkscreen Top")
		(7 "B.SilkS" user "Ref Des/Silkscreen Bottom")
		(1 "F.Mask" user "Board Geometry/Soldermask Top")
		(3 "B.Mask" user "Board Geometry/Soldermask Bottom")
		(17 "Dwgs.User" user "User.Drawings")
		(19 "Cmts.User" user "User.Comments")
		(21 "Eco1.User" user "User.Eco1")
		(23 "Eco2.User" user "User.Eco2")
		(25 "Edge.Cuts" user "Board Geometry/Outline")
		(27 "Margin" user)
		(31 "F.CrtYd" user "Package Geometry/Place Bound Top")
		(29 "B.CrtYd" user "Package Geometry/Place Bound Bottom")
		(35 "F.Fab" user "Ref Des/Assembly Top")
		(33 "B.Fab" user "Ref Des/Assembly Bottom")
	)
	(footprint ""
		(layer "B.Cu")
		(at 231.288336 -125.377194 180)
		(property "Reference" "R1543"
			(at 0 0 0)
			(layer "B.SilkS")
			(hide yes)
			(effects
				(font
					(size 1.27 1.27)
				)
				(justify mirror)
			)
		)
		(property "Value" ""
			(at 0 0 0)
			(layer "B.Fab")
			(effects
				(font
					(size 1.27 1.27)
				)
				(justify mirror)
			)
		)
		(duplicate_pad_numbers_are_jumpers no)
		(fp_line
			(start 0.7874 0.4064)
			(end 0.7874 -0.4064)
			(stroke
				(width 0.1524)
				(type default)
			)
			(layer "B.SilkS")
		)
		(fp_line
			(start 0.7874 -0.4064)
			(end -0.7874 -0.4064)
			(stroke
				(width 0.1524)
				(type default)
			)
			(layer "B.SilkS")
		)
		(fp_line
			(start -0.7874 0.4064)
			(end 0.7874 0.4064)
			(stroke
				(width 0.1524)
				(type default)
			)
			(layer "B.SilkS")
		)
		(fp_line
			(start -0.7874 -0.4064)
			(end -0.7874 0.4064)
			(stroke
				(width 0.1524)
				(type default)
			)
			(layer "B.SilkS")
		)
		(fp_line
			(start 0.67945 0.3048)
			(end 0.67945 -0.305054)
			(stroke
				(width 0.1)
				(type default)
			)
			(layer "B.Fab")
		)
		(fp_line
			(start 0.67945 -0.305054)
			(end 0.12065 -0.305054)
			(stroke
				(width 0.1)
				(type default)
			)
			(layer "B.Fab")
		)
		(fp_line
			(start 0.12065 0.3048)
			(end 0.67945 0.3048)
			(stroke
				(width 0.1)
				(type default)
			)
			(layer "B.Fab")
		)
		(fp_line
			(start 0.12065 0.2794)
			(end 0.12065 0.3048)
			(stroke
				(width 0.1)
				(type default)
			)
			(layer "B.Fab")
		)
		(fp_line
			(start 0.12065 -0.2794)
			(end -0.12065 -0.2794)
			(stroke
				(width 0.1)
				(type default)
			)
			(layer "B.Fab")
		)
		(fp_line
			(start 0.12065 -0.305054)
			(end 0.12065 -0.2794)
			(stroke
				(width 0.1)
				(type default)
			)
			(layer "B.Fab")
		)
		(fp_line
			(start -0.120396 0.3048)
			(end -0.120396 0.2794)
			(stroke
				(width 0.1)
				(type default)
			)
			(layer "B.Fab")
		)
		(fp_line
			(start -0.120396 0.2794)
			(end 0.12065 0.2794)
			(stroke
				(width 0.1)
				(type default)
			)
			(layer "B.Fab")
		)
		(fp_line
			(start -0.12065 -0.2794)
			(end -0.12065 -0.3048)
			(stroke
				(width 0.1)
				(type default)
			)
			(layer "B.Fab")
		)
		(fp_line
			(start -0.12065 -0.3048)
			(end -0.67945 -0.3048)
			(stroke
				(width 0.1)
				(type default)
			)
			(layer "B.Fab")
		)
		(fp_line
			(start -0.67945 0.3048)
			(end -0.120396 0.3048)
			(stroke
				(width 0.1)
				(type default)
			)
			(layer "B.Fab")
		)
		(fp_line
			(start -0.67945 -0.3048)
			(end -0.67945 0.3048)
			(stroke
				(width 0.1)
				(type default)
			)
			(layer "B.Fab")
		)
		(pad "1" smd circle
			(at 0.40005 0)
			(size 0 0)
			(layers "B.Cu" "B.Mask" "B.Paste")
			(net "OCP_SFF_CLK_OE_N")
		)
		(pad "2" smd circle
			(at -0.40005 0)
			(size 0 0)
			(layers "B.Cu" "B.Mask" "B.Paste")
			(net "FM_DB2000_9_OE_N")
		)
	)
	(footprint ""
		(layer "B.Cu")
		(at 111.621316 -360.847386)
		(property "Reference" "PR313"
			(at 0 0 0)
			(layer "B.SilkS")
			(hide yes)
			(effects
				(font
					(size 1.27 1.27)
				)
				(justify mirror)
			)
		)
		(property "Value" ""
			(at 0 0 0)
			(layer "B.Fab")
			(effects
				(font
					(size 1.27 1.27)
				)
				(justify mirror)
			)
		)
		(duplicate_pad_numbers_are_jumpers no)
		(fp_line
			(start -0.7874 -0.4064)
			(end -0.7874 0.4064)
			(stroke
				(width 0.1524)
				(type default)
			)
			(layer "B.SilkS")
		)
		(fp_line
			(start -0.7874 0.4064)
			(end 0.7874 0.4064)
			(stroke
				(width 0.1524)
				(type default)
			)
			(layer "B.SilkS")
		)
		(fp_line
			(start 0.7874 -0.4064)
			(end -0.7874 -0.4064)
			(stroke
				(width 0.1524)
				(type default)
			)
			(layer "B.SilkS")
		)
		(fp_line
			(start 0.7874 0.4064)
			(end 0.7874 -0.4064)
			(stroke
				(width 0.1524)
				(type default)
			)
			(layer "B.SilkS")
		)
		(fp_line
			(start -0.67945 -0.3048)
			(end -0.67945 0.3048)
			(stroke
				(width 0.1)
				(type default)
			)
			(layer "B.Fab")
		)
		(fp_line
			(start -0.67945 0.3048)
			(end -0.120396 0.3048)
			(stroke
				(width 0.1)
				(type default)
			)
			(layer "B.Fab")
		)
		(fp_line
			(start -0.12065 -0.3048)
			(end -0.67945 -0.3048)
			(stroke
				(width 0.1)
				(type default)
			)
			(layer "B.Fab")
		)
		(fp_line
			(start -0.12065 -0.2794)
			(end -0.12065 -0.3048)
			(stroke
				(width 0.1)
				(type default)
			)
			(layer "B.Fab")
		)
		(fp_line
			(start -0.120396 0.2794)
			(end 0.12065 0.2794)
			(stroke
				(width 0.1)
				(type default)
			)
			(layer "B.Fab")
		)
		(fp_line
			(start -0.120396 0.3048)
			(end -0.120396 0.2794)
			(stroke
				(width 0.1)
				(type default)
			)
			(layer "B.Fab")
		)
		(fp_line
			(start 0.12065 -0.305054)
			(end 0.12065 -0.2794)
			(stroke
				(width 0.1)
				(type default)
			)
			(layer "B.Fab")
		)
		(fp_line
			(start 0.12065 -0.2794)
			(end -0.12065 -0.2794)
			(stroke
				(width 0.1)
				(type default)
			)
			(layer "B.Fab")
		)
		(fp_line
			(start 0.12065 0.2794)
			(end 0.12065 0.3048)
			(stroke
				(width 0.1)
				(type default)
			)
			(layer "B.Fab")
		)
		(fp_line
			(start 0.12065 0.3048)
			(end 0.67945 0.3048)
			(stroke
				(width 0.1)
				(type default)
			)
			(layer "B.Fab")
		)
		(fp_line
			(start 0.67945 -0.305054)
			(end 0.12065 -0.305054)
			(stroke
				(width 0.1)
				(type default)
			)
			(layer "B.Fab")
		)
		(fp_line
			(start 0.67945 0.3048)
			(end 0.67945 -0.305054)
			(stroke
				(width 0.1)
				(type default)
			)
			(layer "B.Fab")
		)
		(pad "1" smd circle
			(at 0.40005 0 180)
			(size 0 0)
			(layers "B.Cu" "B.Mask" "B.Paste")
			(net "PVCCIN_CPU1_VIN_CSNIN")
		)
		(pad "2" smd circle
			(at -0.40005 0 180)
			(size 0 0)
			(layers "B.Cu" "B.Mask" "B.Paste")
			(net "GND")
		)
	)
)
